(kicad_pcb
	(version 20260206)
	(generator "pcbnew")
	(generator_version "10.0")
	(general
		(thickness 1.6)
		(legacy_teardrops no)
	)
	(paper "A4")
	(title_block
		(title "04192023_DAF0TMB3IC0_F0TG_MB_C_brd_V02_OCP.brd")
		(comment 1 "Grand Teton / footprints 3379-3386 of 8354")
	)
	(layers
		(0 "F.Cu" signal "TOP")
		(4 "In1.Cu" signal "GND")
		(6 "In2.Cu" signal "IN1")
		(8 "In3.Cu" signal "GND1")
		(10 "In4.Cu" signal "IN2")
		(12 "In5.Cu" signal "GND2")
		(14 "In6.Cu" signal "IN3")
		(16 "In7.Cu" signal "GND3")
		(18 "In8.Cu" signal "VCC")
		(20 "In9.Cu" signal "VCC1")
		(22 "In10.Cu" signal "GND4")
		(24 "In11.Cu" signal "IN4")
		(26 "In12.Cu" signal "GND5")
		(28 "In13.Cu" signal "IN5")
		(30 "In14.Cu" signal "GND6")
		(32 "In15.Cu" signal "IN6")
		(34 "In16.Cu" signal "GND7")
		(2 "B.Cu" signal "BOTTOM")
		(9 "F.Adhes" user "F.Adhesive")
		(11 "B.Adhes" user "B.Adhesive")
		(13 "F.Paste" user "Package Geometry/Pastemask Top")
		(15 "B.Paste" user "Package Geometry/Pastemask Bottom")
		(5 "F.SilkS" user "Ref Des/Silkscreen Top")
		(7 "B.SilkS" user "Ref Des/Silkscreen Bottom")
		(1 "F.Mask" user "Board Geometry/Soldermask Top")
		(3 "B.Mask" user "Board Geometry/Soldermask Bottom")
		(17 "Dwgs.User" user "User.Drawings")
		(19 "Cmts.User" user "User.Comments")
		(21 "Eco1.User" user "User.Eco1")
		(23 "Eco2.User" user "User.Eco2")
		(25 "Edge.Cuts" user "Board Geometry/Outline")
		(27 "Margin" user)
		(31 "F.CrtYd" user "Package Geometry/Place Bound Top")
		(29 "B.CrtYd" user "Package Geometry/Place Bound Bottom")
		(35 "F.Fab" user "Ref Des/Assembly Top")
		(33 "B.Fab" user "Ref Des/Assembly Bottom")
	)
	(footprint ""
		(layer "F.Cu")
		(at 259.834126 -98.746056 180)
		(property "Reference" "R1635"
			(at 0 0 180)
			(layer "F.SilkS")
			(hide yes)
			(effects
				(font
					(size 1.27 1.27)
				)
			)
		)
		(property "Value" ""
			(at 0 0 180)
			(layer "F.Fab")
			(effects
				(font
					(size 1.27 1.27)
				)
			)
		)
		(duplicate_pad_numbers_are_jumpers no)
		(fp_line
			(start 0.7874 0.4064)
			(end -0.7874 0.4064)
			(stroke
				(width 0.1524)
				(type default)
			)
			(layer "F.SilkS")
		)
		(fp_line
			(start 0.7874 -0.4064)
			(end 0.7874 0.4064)
			(stroke
				(width 0.1524)
				(type default)
			)
			(layer "F.SilkS")
		)
		(fp_line
			(start -0.7874 0.4064)
			(end -0.7874 -0.4064)
			(stroke
				(width 0.1524)
				(type default)
			)
			(layer "F.SilkS")
		)
		(fp_line
			(start -0.7874 -0.4064)
			(end 0.7874 -0.4064)
			(stroke
				(width 0.1524)
				(type default)
			)
			(layer "F.SilkS")
		)
		(fp_line
			(start 0.67945 0.3048)
			(end 0.120396 0.3048)
			(stroke
				(width 0.1)
				(type default)
			)
			(layer "F.Fab")
		)
		(fp_line
			(start 0.67945 -0.3048)
			(end 0.67945 0.3048)
			(stroke
				(width 0.1)
				(type default)
			)
			(layer "F.Fab")
		)
		(fp_line
			(start 0.12065 -0.2794)
			(end 0.12065 -0.3048)
			(stroke
				(width 0.1)
				(type default)
			)
			(layer "F.Fab")
		)
		(fp_line
			(start 0.12065 -0.3048)
			(end 0.67945 -0.3048)
			(stroke
				(width 0.1)
				(type default)
			)
			(layer "F.Fab")
		)
		(fp_line
			(start 0.120396 0.3048)
			(end 0.120396 0.2794)
			(stroke
				(width 0.1)
				(type default)
			)
			(layer "F.Fab")
		)
		(fp_line
			(start 0.120396 0.2794)
			(end -0.12065 0.2794)
			(stroke
				(width 0.1)
				(type default)
			)
			(layer "F.Fab")
		)
		(fp_line
			(start -0.12065 0.3048)
			(end -0.67945 0.3048)
			(stroke
				(width 0.1)
				(type default)
			)
			(layer "F.Fab")
		)
		(fp_line
			(start -0.12065 0.2794)
			(end -0.12065 0.3048)
			(stroke
				(width 0.1)
				(type default)
			)
			(layer "F.Fab")
		)
		(fp_line
			(start -0.12065 -0.2794)
			(end 0.12065 -0.2794)
			(stroke
				(width 0.1)
				(type default)
			)
			(layer "F.Fab")
		)
		(fp_line
			(start -0.12065 -0.305054)
			(end -0.12065 -0.2794)
			(stroke
				(width 0.1)
				(type default)
			)
			(layer "F.Fab")
		)
		(fp_line
			(start -0.67945 0.3048)
			(end -0.67945 -0.305054)
			(stroke
				(width 0.1)
				(type default)
			)
			(layer "F.Fab")
		)
		(fp_line
			(start -0.67945 -0.305054)
			(end -0.12065 -0.305054)
			(stroke
				(width 0.1)
				(type default)
			)
			(layer "F.Fab")
		)
		(pad "1" smd circle
			(at -0.40005 0 180)
			(size 0 0)
			(layers "F.Cu" "F.Mask" "F.Paste")
			(net "JTAG_TRST_R_N")
		)
		(pad "2" smd circle
			(at 0.40005 0 180)
			(size 0 0)
			(layers "F.Cu" "F.Mask" "F.Paste")
			(net "JTAG_TRST_N")
		)
	)
	(footprint ""
		(layer "F.Cu")
		(at 259.568696 -39.754556 90)
		(property "Reference" "PD114"
			(at -2.56032 1.848612 90)
			(unlocked yes)
			(layer "F.SilkS")
			(effects
				(font
					(size 0.7874 0.5842)
					(thickness 0.1524)
				)
				(justify left)
			)
		)
		(property "Value" ""
			(at 0 0 90)
			(layer "F.Fab")
			(effects
				(font
					(size 1.27 1.27)
				)
			)
		)
		(duplicate_pad_numbers_are_jumpers no)
		(fp_line
			(start 2.631186 -0.999998)
			(end -2.250186 -0.999998)
			(stroke
				(width 0.1524)
				(type default)
			)
			(layer "F.SilkS")
		)
		(fp_line
			(start -2.250186 -0.999998)
			(end -2.250186 0.999998)
			(stroke
				(width 0.1524)
				(type default)
			)
			(layer "F.SilkS")
		)
		(fp_line
			(start 0.381 -0.4318)
			(end 0.381 0.3302)
			(stroke
				(width 0.1524)
				(type default)
			)
			(layer "F.SilkS")
		)
		(fp_line
			(start -0.381 -0.4318)
			(end 0.381 -0.0508)
			(stroke
				(width 0.1524)
				(type default)
			)
			(layer "F.SilkS")
		)
		(fp_line
			(start 0.381 -0.0508)
			(end 0.635 -0.0508)
			(stroke
				(width 0.1524)
				(type default)
			)
			(layer "F.SilkS")
		)
		(fp_line
			(start 0.381 -0.0508)
			(end -0.381 0.3302)
			(stroke
				(width 0.1524)
				(type default)
			)
			(layer "F.SilkS")
		)
		(fp_line
			(start -0.381 -0.0508)
			(end -0.6604 -0.0508)
			(stroke
				(width 0.1524)
				(type default)
			)
			(layer "F.SilkS")
		)
		(fp_line
			(start -0.381 0.3302)
			(end -0.381 -0.4318)
			(stroke
				(width 0.1524)
				(type default)
			)
			(layer "F.SilkS")
		)
		(fp_line
			(start 2.631186 0.999998)
			(end 2.631186 -0.999998)
			(stroke
				(width 0.1524)
				(type default)
			)
			(layer "F.SilkS")
		)
		(fp_line
			(start -2.250186 0.999998)
			(end 2.631186 0.999998)
			(stroke
				(width 0.1524)
				(type default)
			)
			(layer "F.SilkS")
		)
		(fp_rect
			(start 2.1844 -0.9652)
			(end 2.6162 1.016)
			(stroke
				(width 0)
				(type default)
			)
			(fill yes)
			(layer "F.SilkS")
		)
		(fp_line
			(start 1.450086 -0.999998)
			(end -1.450086 -0.999998)
			(stroke
				(width 0.1)
				(type default)
			)
			(layer "F.Fab")
		)
		(fp_line
			(start -1.450086 -0.999998)
			(end -1.450086 0.999998)
			(stroke
				(width 0.1)
				(type default)
			)
			(layer "F.Fab")
		)
		(fp_line
			(start 1.450086 0.999998)
			(end 1.450086 -0.999998)
			(stroke
				(width 0.1)
				(type default)
			)
			(layer "F.Fab")
		)
		(fp_line
			(start -1.450086 0.999998)
			(end 1.450086 0.999998)
			(stroke
				(width 0.1)
				(type default)
			)
			(layer "F.Fab")
		)
		(fp_text user "+"
			(at -3.885946 -0.282448 90)
			(unlocked yes)
			(layer "F.SilkS")
			(effects
				(font
					(size 1.905 1.4224)
					(thickness 0.1524)
				)
				(justify left)
			)
		)
		(fp_text user "-"
			(at 2.4384 -0.22225 90)
			(unlocked yes)
			(layer "F.SilkS")
			(effects
				(font
					(size 1.905 1.4224)
					(thickness 0.1524)
				)
				(justify left)
			)
		)
		(fp_text user "-"
			(at 2.4384 -0.22225 90)
			(unlocked yes)
			(layer "F.Fab")
			(effects
				(font
					(size 1.905 1.4224)
					(thickness 0.1524)
				)
				(justify left)
			)
		)
		(fp_text user "+"
			(at -3.4798 -0.22225 90)
			(unlocked yes)
			(layer "F.Fab")
			(effects
				(font
					(size 1.905 1.4224)
					(thickness 0.1524)
				)
				(justify left)
			)
		)
		(pad "A" smd rect
			(at -1.450086 0 90)
			(size 1.3208 1.4224)
			(layers "F.Cu" "F.Mask" "F.Paste")
			(net "GND")
		)
		(pad "C" smd rect
			(at 1.450086 0 90)
			(size 1.3208 1.4224)
			(layers "F.Cu" "F.Mask" "F.Paste")
			(net "P12V_AUX")
		)
	)
	(footprint ""
		(layer "F.Cu")
		(at 105.960164 -258.405376)
		(property "Reference" "C2260"
			(at 0 0 0)
			(layer "F.SilkS")
			(hide yes)
			(effects
				(font
					(size 1.27 1.27)
				)
			)
		)
		(property "Value" ""
			(at 0 0 0)
			(layer "F.Fab")
			(effects
				(font
					(size 1.27 1.27)
				)
			)
		)
		(duplicate_pad_numbers_are_jumpers no)
		(fp_line
			(start -0.7874 -0.4064)
			(end 0.7874 -0.4064)
			(stroke
				(width 0.1524)
				(type default)
			)
			(layer "F.SilkS")
		)
		(fp_line
			(start -0.7874 0.4064)
			(end -0.7874 -0.4064)
			(stroke
				(width 0.1524)
				(type default)
			)
			(layer "F.SilkS")
		)
		(fp_line
			(start 0.7874 -0.4064)
			(end 0.7874 0.4064)
			(stroke
				(width 0.1524)
				(type default)
			)
			(layer "F.SilkS")
		)
		(fp_line
			(start 0.7874 0.4064)
			(end -0.7874 0.4064)
			(stroke
				(width 0.1524)
				(type default)
			)
			(layer "F.SilkS")
		)
		(fp_line
			(start -0.67945 -0.305054)
			(end -0.12065 -0.305054)
			(stroke
				(width 0.1)
				(type default)
			)
			(layer "F.Fab")
		)
		(fp_line
			(start -0.67945 0.3048)
			(end -0.67945 -0.305054)
			(stroke
				(width 0.1)
				(type default)
			)
			(layer "F.Fab")
		)
		(fp_line
			(start -0.12065 -0.305054)
			(end -0.12065 -0.2794)
			(stroke
				(width 0.1)
				(type default)
			)
			(layer "F.Fab")
		)
		(fp_line
			(start -0.12065 -0.2794)
			(end 0.12065 -0.2794)
			(stroke
				(width 0.1)
				(type default)
			)
			(layer "F.Fab")
		)
		(fp_line
			(start -0.12065 0.2794)
			(end -0.12065 0.3048)
			(stroke
				(width 0.1)
				(type default)
			)
			(layer "F.Fab")
		)
		(fp_line
			(start -0.12065 0.3048)
			(end -0.67945 0.3048)
			(stroke
				(width 0.1)
				(type default)
			)
			(layer "F.Fab")
		)
		(fp_line
			(start 0.120396 0.2794)
			(end -0.12065 0.2794)
			(stroke
				(width 0.1)
				(type default)
			)
			(layer "F.Fab")
		)
		(fp_line
			(start 0.120396 0.3048)
			(end 0.120396 0.2794)
			(stroke
				(width 0.1)
				(type default)
			)
			(layer "F.Fab")
		)
		(fp_line
			(start 0.12065 -0.3048)
			(end 0.67945 -0.3048)
			(stroke
				(width 0.1)
				(type default)
			)
			(layer "F.Fab")
		)
		(fp_line
			(start 0.12065 -0.2794)
			(end 0.12065 -0.3048)
			(stroke
				(width 0.1)
				(type default)
			)
			(layer "F.Fab")
		)
		(fp_line
			(start 0.67945 -0.3048)
			(end 0.67945 0.3048)
			(stroke
				(width 0.1)
				(type default)
			)
			(layer "F.Fab")
		)
		(fp_line
			(start 0.67945 0.3048)
			(end 0.120396 0.3048)
			(stroke
				(width 0.1)
				(type default)
			)
			(layer "F.Fab")
		)
		(pad "1" smd circle
			(at -0.40005 0)
			(size 0 0)
			(layers "F.Cu" "F.Mask" "F.Paste")
			(net "PVDDIO_P1")
		)
		(pad "2" smd circle
			(at 0.40005 0)
			(size 0 0)
			(layers "F.Cu" "F.Mask" "F.Paste")
			(net "GND")
		)
	)
	(footprint ""
		(layer "F.Cu")
		(at 297.688 -108.966 -90)
		(property "Reference" "R1348"
			(at 0 0 270)
			(layer "F.SilkS")
			(hide yes)
			(effects
				(font
					(size 1.27 1.27)
				)
			)
		)
		(property "Value" ""
			(at 0 0 270)
			(layer "F.Fab")
			(effects
				(font
					(size 1.27 1.27)
				)
			)
		)
		(duplicate_pad_numbers_are_jumpers no)
		(fp_line
			(start -0.7874 0.4064)
			(end -0.7874 -0.4064)
			(stroke
				(width 0.1524)
				(type default)
			)
			(layer "F.SilkS")
		)
		(fp_line
			(start 0.7874 0.4064)
			(end -0.7874 0.4064)
			(stroke
				(width 0.1524)
				(type default)
			)
			(layer "F.SilkS")
		)
		(fp_line
			(start -0.7874 -0.4064)
			(end 0.7874 -0.4064)
			(stroke
				(width 0.1524)
				(type default)
			)
			(layer "F.SilkS")
		)
		(fp_line
			(start 0.7874 -0.4064)
			(end 0.7874 0.4064)
			(stroke
				(width 0.1524)
				(type default)
			)
			(layer "F.SilkS")
		)
		(fp_line
			(start -0.67945 0.3048)
			(end -0.67945 -0.305054)
			(stroke
				(width 0.1)
				(type default)
			)
			(layer "F.Fab")
		)
		(fp_line
			(start -0.12065 0.3048)
			(end -0.67945 0.3048)
			(stroke
				(width 0.1)
				(type default)
			)
			(layer "F.Fab")
		)
		(fp_line
			(start 0.120396 0.3048)
			(end 0.120396 0.2794)
			(stroke
				(width 0.1)
				(type default)
			)
			(layer "F.Fab")
		)
		(fp_line
			(start 0.67945 0.3048)
			(end 0.120396 0.3048)
			(stroke
				(width 0.1)
				(type default)
			)
			(layer "F.Fab")
		)
		(fp_line
			(start -0.12065 0.2794)
			(end -0.12065 0.3048)
			(stroke
				(width 0.1)
				(type default)
			)
			(layer "F.Fab")
		)
		(fp_line
			(start 0.120396 0.2794)
			(end -0.12065 0.2794)
			(stroke
				(width 0.1)
				(type default)
			)
			(layer "F.Fab")
		)
		(fp_line
			(start -0.12065 -0.2794)
			(end 0.12065 -0.2794)
			(stroke
				(width 0.1)
				(type default)
			)
			(layer "F.Fab")
		)
		(fp_line
			(start 0.12065 -0.2794)
			(end 0.12065 -0.3048)
			(stroke
				(width 0.1)
				(type default)
			)
			(layer "F.Fab")
		)
		(fp_line
			(start 0.12065 -0.3048)
			(end 0.67945 -0.3048)
			(stroke
				(width 0.1)
				(type default)
			)
			(layer "F.Fab")
		)
		(fp_line
			(start 0.67945 -0.3048)
			(end 0.67945 0.3048)
			(stroke
				(width 0.1)
				(type default)
			)
			(layer "F.Fab")
		)
		(fp_line
			(start -0.67945 -0.305054)
			(end -0.12065 -0.305054)
			(stroke
				(width 0.1)
				(type default)
			)
			(layer "F.Fab")
		)
		(fp_line
			(start -0.12065 -0.305054)
			(end -0.12065 -0.2794)
			(stroke
				(width 0.1)
				(type default)
			)
			(layer "F.Fab")
		)
		(pad "1" smd circle
			(at -0.40005 0 270)
			(size 0 0)
			(layers "F.Cu" "F.Mask" "F.Paste")
			(net "SMB_INA230_3V3AUX_SCL")
		)
		(pad "2" smd circle
			(at 0.40005 0 270)
			(size 0 0)
			(layers "F.Cu" "F.Mask" "F.Paste")
			(net "SMB_INA230_8_3V3AUX_SCL_R")
		)
	)
	(footprint ""
		(layer "F.Cu")
		(at 103.951786 -104.674924 180)
		(property "Reference" ""
			(at 0 0 180)
			(layer "F.SilkS")
			(hide yes)
			(effects
				(font
					(size 1.27 1.27)
				)
			)
		)
		(property "Value" ""
			(at 0 0 180)
			(layer "F.Fab")
			(effects
				(font
					(size 1.27 1.27)
				)
			)
		)
		(duplicate_pad_numbers_are_jumpers no)
		(pad "1" smd circle
			(at 0 0 180)
			(size 0.9906 0.9906)
			(layers "F.Cu" "F.Mask" "F.Paste")
			(net "Net_2238")
		)
		(zone
			(layer "F.Cu")
			(hatch none 0.5)
			(connect_pads
				(clearance 0)
			)
			(min_thickness 0.25)
			(keepout
				(tracks not_allowed)
				(vias allowed)
				(pads allowed)
				(copperpour not_allowed)
				(footprints allowed)
			)
			(placement
				(enabled no)
				(sheetname "")
			)
			(fill
				(thermal_gap 0.5)
				(thermal_bridge_width 0.5)
				(island_removal_mode 0)
			)
			(polygon
				(pts
					(arc
						(start 105.577386 -104.674924)
						(mid 102.326186 -104.674924)
						(end 105.577386 -104.674924)
					)
				)
			)
		)
	)
	(footprint ""
		(layer "F.Cu")
		(at 86.420706 -178.359562 180)
		(property "Reference" "PC261_2"
			(at 0 0 180)
			(layer "F.SilkS")
			(hide yes)
			(effects
				(font
					(size 1.27 1.27)
				)
			)
		)
		(property "Value" ""
			(at 0 0 180)
			(layer "F.Fab")
			(effects
				(font
					(size 1.27 1.27)
				)
			)
		)
		(duplicate_pad_numbers_are_jumpers no)
		(fp_line
			(start 0.7874 0.4064)
			(end -0.7874 0.4064)
			(stroke
				(width 0.1524)
				(type default)
			)
			(layer "F.SilkS")
		)
		(fp_line
			(start 0.7874 -0.4064)
			(end 0.7874 0.4064)
			(stroke
				(width 0.1524)
				(type default)
			)
			(layer "F.SilkS")
		)
		(fp_line
			(start -0.7874 0.4064)
			(end -0.7874 -0.4064)
			(stroke
				(width 0.1524)
				(type default)
			)
			(layer "F.SilkS")
		)
		(fp_line
			(start -0.7874 -0.4064)
			(end 0.7874 -0.4064)
			(stroke
				(width 0.1524)
				(type default)
			)
			(layer "F.SilkS")
		)
		(fp_line
			(start 0.67945 0.3048)
			(end 0.120396 0.3048)
			(stroke
				(width 0.1)
				(type default)
			)
			(layer "F.Fab")
		)
		(fp_line
			(start 0.67945 -0.3048)
			(end 0.67945 0.3048)
			(stroke
				(width 0.1)
				(type default)
			)
			(layer "F.Fab")
		)
		(fp_line
			(start 0.12065 -0.2794)
			(end 0.12065 -0.3048)
			(stroke
				(width 0.1)
				(type default)
			)
			(layer "F.Fab")
		)
		(fp_line
			(start 0.12065 -0.3048)
			(end 0.67945 -0.3048)
			(stroke
				(width 0.1)
				(type default)
			)
			(layer "F.Fab")
		)
		(fp_line
			(start 0.120396 0.3048)
			(end 0.120396 0.2794)
			(stroke
				(width 0.1)
				(type default)
			)
			(layer "F.Fab")
		)
		(fp_line
			(start 0.120396 0.2794)
			(end -0.12065 0.2794)
			(stroke
				(width 0.1)
				(type default)
			)
			(layer "F.Fab")
		)
		(fp_line
			(start -0.12065 0.3048)
			(end -0.67945 0.3048)
			(stroke
				(width 0.1)
				(type default)
			)
			(layer "F.Fab")
		)
		(fp_line
			(start -0.12065 0.2794)
			(end -0.12065 0.3048)
			(stroke
				(width 0.1)
				(type default)
			)
			(layer "F.Fab")
		)
		(fp_line
			(start -0.12065 -0.2794)
			(end 0.12065 -0.2794)
			(stroke
				(width 0.1)
				(type default)
			)
			(layer "F.Fab")
		)
		(fp_line
			(start -0.12065 -0.305054)
			(end -0.12065 -0.2794)
			(stroke
				(width 0.1)
				(type default)
			)
			(layer "F.Fab")
		)
		(fp_line
			(start -0.67945 0.3048)
			(end -0.67945 -0.305054)
			(stroke
				(width 0.1)
				(type default)
			)
			(layer "F.Fab")
		)
		(fp_line
			(start -0.67945 -0.305054)
			(end -0.12065 -0.305054)
			(stroke
				(width 0.1)
				(type default)
			)
			(layer "F.Fab")
		)
		(pad "1" smd circle
			(at -0.40005 0 180)
			(size 0 0)
			(layers "F.Cu" "F.Mask" "F.Paste")
			(net "SW_P12V_AUX_PVDDCR_CPU0_P1_FLT")
		)
		(pad "2" smd circle
			(at 0.40005 0 180)
			(size 0 0)
			(layers "F.Cu" "F.Mask" "F.Paste")
			(net "GND")
		)
	)
	(footprint ""
		(layer "F.Cu")
		(at 366.822736 -403.285452 90)
		(property "Reference" "R1096"
			(at 0 0 90)
			(layer "F.SilkS")
			(hide yes)
			(effects
				(font
					(size 1.27 1.27)
				)
			)
		)
		(property "Value" ""
			(at 0 0 90)
			(layer "F.Fab")
			(effects
				(font
					(size 1.27 1.27)
				)
			)
		)
		(duplicate_pad_numbers_are_jumpers no)
		(fp_line
			(start 0.32512 -0.175006)
			(end 0.32512 0.175006)
			(stroke
				(width 0.1)
				(type default)
			)
			(layer "F.Fab")
		)
		(fp_line
			(start -0.32512 -0.175006)
			(end 0.32512 -0.175006)
			(stroke
				(width 0.1)
				(type default)
			)
			(layer "F.Fab")
		)
		(fp_line
			(start 0.32512 0.175006)
			(end -0.32512 0.175006)
			(stroke
				(width 0.1)
				(type default)
			)
			(layer "F.Fab")
		)
		(fp_line
			(start -0.32512 0.175006)
			(end -0.32512 -0.175006)
			(stroke
				(width 0.1)
				(type default)
			)
			(layer "F.Fab")
		)
		(pad "1" smd rect
			(at -0.2667 0 90)
			(size 0.3048 0.381)
			(layers "F.Cu" "F.Mask" "F.Paste")
			(net "RST_RT_CPU0_P3_RESET_N")
		)
		(pad "2" smd rect
			(at 0.2667 0 270)
			(size 0.3048 0.381)
			(layers "F.Cu" "F.Mask" "F.Paste")
			(net "RST_RT_CPU0_P3_RESET_R_N")
		)
	)
	(footprint ""
		(layer "F.Cu")
		(at 43.265852 -383.7432)
		(property "Reference" "R725"
			(at 0 0 0)
			(layer "F.SilkS")
			(hide yes)
			(effects
				(font
					(size 1.27 1.27)
				)
			)
		)
		(property "Value" ""
			(at 0 0 0)
			(layer "F.Fab")
			(effects
				(font
					(size 1.27 1.27)
				)
			)
		)
		(duplicate_pad_numbers_are_jumpers no)
		(fp_line
			(start -0.32512 -0.175006)
			(end 0.32512 -0.175006)
			(stroke
				(width 0.1)
				(type default)
			)
			(layer "F.Fab")
		)
		(fp_line
			(start -0.32512 0.175006)
			(end -0.32512 -0.175006)
			(stroke
				(width 0.1)
				(type default)
			)
			(layer "F.Fab")
		)
		(fp_line
			(start 0.32512 -0.175006)
			(end 0.32512 0.175006)
			(stroke
				(width 0.1)
				(type default)
			)
			(layer "F.Fab")
		)
		(fp_line
			(start 0.32512 0.175006)
			(end -0.32512 0.175006)
			(stroke
				(width 0.1)
				(type default)
			)
			(layer "F.Fab")
		)
		(pad "1" smd rect
			(at -0.2667 0)
			(size 0.3048 0.381)
			(layers "F.Cu" "F.Mask" "F.Paste")
			(net "TEST2_RT_CPU1_P0")
		)
		(pad "2" smd rect
			(at 0.2667 0 180)
			(size 0.3048 0.381)
			(layers "F.Cu" "F.Mask" "F.Paste")
			(net "GND")
		)
	)
)
